# S9S_MB_2U (Grand Teton) — schematic netlist excerpt (pin names and nets, part order shuffled) for the footprints in the layout excerpt that follows; sources: Cadence DE-HDL packaged netlist, KiCad conversion of 03242023_DA0F0TMBIJ0_F0T_Motherboard_J_brd_V01_OCP.brd

PC2093  Q_CAP  1UF 25V 10% X6S  pkg C0402  page 156 : A = GND ; B = P3V3_OCP_REG_1
R1276  Q_RES  22 1% CHIP  pkg 0402LF  page 209 : A = CLK_100M_OCP_SFF_3_R_DN ; B = CLK_100M_OCP_SFF_3_DN

(kicad_pcb
	(version 20260206)
	(generator "pcbnew")
	(generator_version "10.0")
	(general
		(thickness 1.6)
		(legacy_teardrops no)
	)
	(paper "A4")
	(title_block
		(title "03242023_DA0F0TMBIJ0_F0T_Motherboard_J_brd_V01_OCP.brd")
		(comment 1 "Grand Teton / footprints 4064-4065 of 6105")
	)
	(layers
		(0 "F.Cu" signal "TOP")
		(4 "In1.Cu" signal "GND")
		(6 "In2.Cu" signal "IN1")
		(8 "In3.Cu" signal "GND1")
		(10 "In4.Cu" signal "IN2")
		(12 "In5.Cu" signal "GND2")
		(14 "In6.Cu" signal "IN3")
		(16 "In7.Cu" signal "GND3")
		(18 "In8.Cu" signal "VCC")
		(20 "In9.Cu" signal "VCC1")
		(22 "In10.Cu" signal "GND4")
		(24 "In11.Cu" signal "IN4")
		(26 "In12.Cu" signal "GND5")
		(28 "In13.Cu" signal "IN5")
		(30 "In14.Cu" signal "GND6")
		(32 "In15.Cu" signal "IN6")
		(34 "In16.Cu" signal "GND7")
		(2 "B.Cu" signal "BOTTOM")
		(9 "F.Adhes" user "F.Adhesive")
		(11 "B.Adhes" user "B.Adhesive")
		(13 "F.Paste" user "Package Geometry/Pastemask Top")
		(15 "B.Paste" user "Package Geometry/Pastemask Bottom")
		(5 "F.SilkS" user "Ref Des/Silkscreen Top")
		(7 "B.SilkS" user "Ref Des/Silkscreen Bottom")
		(1 "F.Mask" user "Board Geometry/Soldermask Top")
		(3 "B.Mask" user "Board Geometry/Soldermask Bottom")
		(17 "Dwgs.User" user "User.Drawings")
		(19 "Cmts.User" user "User.Comments")
		(21 "Eco1.User" user "User.Eco1")
		(23 "Eco2.User" user "User.Eco2")
		(25 "Edge.Cuts" user "Board Geometry/Outline")
		(27 "Margin" user)
		(31 "F.CrtYd" user "Package Geometry/Place Bound Top")
		(29 "B.CrtYd" user "Package Geometry/Place Bound Bottom")
		(35 "F.Fab" user "Ref Des/Assembly Top")
		(33 "B.Fab" user "Ref Des/Assembly Bottom")
	)
	(footprint ""
		(layer "F.Cu")
		(at 231.976422 -117.710712 -90)
		(property "Reference" "R1276"
			(at 0 0 270)
			(layer "F.SilkS")
			(hide yes)
			(effects
				(font
					(size 1.27 1.27)
				)
			)
		)
		(property "Value" ""
			(at 0 0 270)
			(layer "F.Fab")
			(effects
				(font
					(size 1.27 1.27)
				)
			)
		)
		(duplicate_pad_numbers_are_jumpers no)
		(fp_line
			(start 0.418592 0.4064)
			(end -0.373888 0.4064)
			(stroke
				(width 0.1524)
				(type default)
			)
			(layer "F.SilkS")
		)
		(fp_line
			(start -0.7874 -0.006858)
			(end -0.7874 -0.4064)
			(stroke
				(width 0.1524)
				(type default)
			)
			(layer "F.SilkS")
		)
		(fp_line
			(start -0.7874 -0.4064)
			(end 0.7874 -0.4064)
			(stroke
				(width 0.1524)
				(type default)
			)
			(layer "F.SilkS")
		)
		(fp_line
			(start 0.7874 -0.4064)
			(end 0.7874 0.079502)
			(stroke
				(width 0.1524)
				(type default)
			)
			(layer "F.SilkS")
		)
		(fp_line
			(start -0.67945 0.3048)
			(end -0.67945 -0.305054)
			(stroke
				(width 0.1)
				(type default)
			)
			(layer "F.Fab")
		)
		(fp_line
			(start -0.12065 0.3048)
			(end -0.67945 0.3048)
			(stroke
				(width 0.1)
				(type default)
			)
			(layer "F.Fab")
		)
		(fp_line
			(start 0.120396 0.3048)
			(end 0.120396 0.2794)
			(stroke
				(width 0.1)
				(type default)
			)
			(layer "F.Fab")
		)
		(fp_line
			(start 0.67945 0.3048)
			(end 0.120396 0.3048)
			(stroke
				(width 0.1)
				(type default)
			)
			(layer "F.Fab")
		)
		(fp_line
			(start -0.12065 0.2794)
			(end -0.12065 0.3048)
			(stroke
				(width 0.1)
				(type default)
			)
			(layer "F.Fab")
		)
		(fp_line
			(start 0.120396 0.2794)
			(end -0.12065 0.2794)
			(stroke
				(width 0.1)
				(type default)
			)
			(layer "F.Fab")
		)
		(fp_line
			(start -0.12065 -0.2794)
			(end 0.12065 -0.2794)
			(stroke
				(width 0.1)
				(type default)
			)
			(layer "F.Fab")
		)
		(fp_line
			(start 0.12065 -0.2794)
			(end 0.12065 -0.3048)
			(stroke
				(width 0.1)
				(type default)
			)
			(layer "F.Fab")
		)
		(fp_line
			(start 0.12065 -0.3048)
			(end 0.67945 -0.3048)
			(stroke
				(width 0.1)
				(type default)
			)
			(layer "F.Fab")
		)
		(fp_line
			(start 0.67945 -0.3048)
			(end 0.67945 0.3048)
			(stroke
				(width 0.1)
				(type default)
			)
			(layer "F.Fab")
		)
		(fp_line
			(start -0.67945 -0.305054)
			(end -0.12065 -0.305054)
			(stroke
				(width 0.1)
				(type default)
			)
			(layer "F.Fab")
		)
		(fp_line
			(start -0.12065 -0.305054)
			(end -0.12065 -0.2794)
			(stroke
				(width 0.1)
				(type default)
			)
			(layer "F.Fab")
		)
		(pad "1" smd circle
			(at -0.40005 0 270)
			(size 0 0)
			(layers "F.Cu" "F.Mask" "F.Paste")
			(net "CLK_100M_OCP_SFF_3_R_DN")
		)
		(pad "2" smd circle
			(at 0.40005 0 270)
			(size 0 0)
			(layers "F.Cu" "F.Mask" "F.Paste")
			(net "CLK_100M_OCP_SFF_3_DN")
		)
	)
	(footprint ""
		(layer "F.Cu")
		(at 430.355756 -109.25937 -90)
		(property "Reference" "PC2093"
			(at 0 0 270)
			(layer "F.SilkS")
			(hide yes)
			(effects
				(font
					(size 1.27 1.27)
				)
			)
		)
		(property "Value" ""
			(at 0 0 270)
			(layer "F.Fab")
			(effects
				(font
					(size 1.27 1.27)
				)
			)
		)
		(duplicate_pad_numbers_are_jumpers no)
		(fp_line
			(start -0.7874 0.4064)
			(end -0.7874 -0.4064)
			(stroke
				(width 0.1524)
				(type default)
			)
			(layer "F.SilkS")
		)
		(fp_line
			(start 0.7874 0.4064)
			(end -0.7874 0.4064)
			(stroke
				(width 0.1524)
				(type default)
			)
			(layer "F.SilkS")
		)
		(fp_line
			(start -0.7874 -0.4064)
			(end 0.7874 -0.4064)
			(stroke
				(width 0.1524)
				(type default)
			)
			(layer "F.SilkS")
		)
		(fp_line
			(start 0.7874 -0.4064)
			(end 0.7874 0.4064)
			(stroke
				(width 0.1524)
				(type default)
			)
			(layer "F.SilkS")
		)
		(fp_line
			(start -0.67945 0.3048)
			(end -0.67945 -0.305054)
			(stroke
				(width 0.1)
				(type default)
			)
			(layer "F.Fab")
		)
		(fp_line
			(start -0.12065 0.3048)
			(end -0.67945 0.3048)
			(stroke
				(width 0.1)
				(type default)
			)
			(layer "F.Fab")
		)
		(fp_line
			(start 0.120396 0.3048)
			(end 0.120396 0.2794)
			(stroke
				(width 0.1)
				(type default)
			)
			(layer "F.Fab")
		)
		(fp_line
			(start 0.67945 0.3048)
			(end 0.120396 0.3048)
			(stroke
				(width 0.1)
				(type default)
			)
			(layer "F.Fab")
		)
		(fp_line
			(start -0.12065 0.2794)
			(end -0.12065 0.3048)
			(stroke
				(width 0.1)
				(type default)
			)
			(layer "F.Fab")
		)
		(fp_line
			(start 0.120396 0.2794)
			(end -0.12065 0.2794)
			(stroke
				(width 0.1)
				(type default)
			)
			(layer "F.Fab")
		)
		(fp_line
			(start -0.12065 -0.2794)
			(end 0.12065 -0.2794)
			(stroke
				(width 0.1)
				(type default)
			)
			(layer "F.Fab")
		)
		(fp_line
			(start 0.12065 -0.2794)
			(end 0.12065 -0.3048)
			(stroke
				(width 0.1)
				(type default)
			)
			(layer "F.Fab")
		)
		(fp_line
			(start 0.12065 -0.3048)
			(end 0.67945 -0.3048)
			(stroke
				(width 0.1)
				(type default)
			)
			(layer "F.Fab")
		)
		(fp_line
			(start 0.67945 -0.3048)
			(end 0.67945 0.3048)
			(stroke
				(width 0.1)
				(type default)
			)
			(layer "F.Fab")
		)
		(fp_line
			(start -0.67945 -0.305054)
			(end -0.12065 -0.305054)
			(stroke
				(width 0.1)
				(type default)
			)
			(layer "F.Fab")
		)
		(fp_line
			(start -0.12065 -0.305054)
			(end -0.12065 -0.2794)
			(stroke
				(width 0.1)
				(type default)
			)
			(layer "F.Fab")
		)
		(pad "1" smd circle
			(at -0.40005 0 270)
			(size 0 0)
			(layers "F.Cu" "F.Mask" "F.Paste")
			(net "GND")
		)
		(pad "2" smd circle
			(at 0.40005 0 270)
			(size 0 0)
			(layers "F.Cu" "F.Mask" "F.Paste")
			(net "P3V3_OCP_REG_1")
		)
	)
)
